# S9S_MB_2U (Grand Teton) — schematic netlist excerpt (pin names and nets, part order shuffled) for the footprints in the layout excerpt that follows; sources: Cadence DE-HDL packaged netlist, KiCad conversion of 03242023_DA0F0TMBIJ0_F0T_Motherboard_J_brd_V01_OCP.brd

PC263_P0_5  Q_CAP  22UF 16V 20% X6S  pkg C0805  page 269 : A = SW_P12V_PVCCIN_CPU0_FLT ; B = GND
R621  Q_RES  1K 1% EMPTY  pkg 0402LF  page 199 : A = P3V3_AUX ; B = FM_PCH_SKIP_RTC_CLOCK
R35  Q_RES  15.4K 1% CHIP  pkg 0402LF  page 91 : A = PD_CHE_CPU0_DIMM2_SAA ; B = GND

(kicad_pcb
	(version 20260206)
	(generator "pcbnew")
	(generator_version "10.0")
	(general
		(thickness 1.6)
		(legacy_teardrops no)
	)
	(paper "A4")
	(title_block
		(title "03242023_DA0F0TMBIJ0_F0T_Motherboard_J_brd_V01_OCP.brd")
		(comment 1 "Grand Teton / footprints 5683-5685 of 6105")
	)
	(layers
		(0 "F.Cu" signal "TOP")
		(4 "In1.Cu" signal "GND")
		(6 "In2.Cu" signal "IN1")
		(8 "In3.Cu" signal "GND1")
		(10 "In4.Cu" signal "IN2")
		(12 "In5.Cu" signal "GND2")
		(14 "In6.Cu" signal "IN3")
		(16 "In7.Cu" signal "GND3")
		(18 "In8.Cu" signal "VCC")
		(20 "In9.Cu" signal "VCC1")
		(22 "In10.Cu" signal "GND4")
		(24 "In11.Cu" signal "IN4")
		(26 "In12.Cu" signal "GND5")
		(28 "In13.Cu" signal "IN5")
		(30 "In14.Cu" signal "GND6")
		(32 "In15.Cu" signal "IN6")
		(34 "In16.Cu" signal "GND7")
		(2 "B.Cu" signal "BOTTOM")
		(9 "F.Adhes" user "F.Adhesive")
		(11 "B.Adhes" user "B.Adhesive")
		(13 "F.Paste" user "Package Geometry/Pastemask Top")
		(15 "B.Paste" user "Package Geometry/Pastemask Bottom")
		(5 "F.SilkS" user "Ref Des/Silkscreen Top")
		(7 "B.SilkS" user "Ref Des/Silkscreen Bottom")
		(1 "F.Mask" user "Board Geometry/Soldermask Top")
		(3 "B.Mask" user "Board Geometry/Soldermask Bottom")
		(17 "Dwgs.User" user "User.Drawings")
		(19 "Cmts.User" user "User.Comments")
		(21 "Eco1.User" user "User.Eco1")
		(23 "Eco2.User" user "User.Eco2")
		(25 "Edge.Cuts" user "Board Geometry/Outline")
		(27 "Margin" user)
		(31 "F.CrtYd" user "Package Geometry/Place Bound Top")
		(29 "B.CrtYd" user "Package Geometry/Place Bound Bottom")
		(35 "F.Fab" user "Ref Des/Assembly Top")
		(33 "B.Fab" user "Ref Des/Assembly Bottom")
	)
	(footprint ""
		(layer "B.Cu")
		(at 378.80036 -341.218012 -90)
		(property "Reference" "PC263_P0_5"
			(at 0 0 90)
			(layer "B.SilkS")
			(hide yes)
			(effects
				(font
					(size 1.27 1.27)
				)
				(justify mirror)
			)
		)
		(property "Value" ""
			(at 0 0 90)
			(layer "B.Fab")
			(effects
				(font
					(size 1.27 1.27)
				)
				(justify mirror)
			)
		)
		(duplicate_pad_numbers_are_jumpers no)
		(fp_line
			(start -1.524 0.762)
			(end 1.524 0.762)
			(stroke
				(width 0.1524)
				(type default)
			)
			(layer "B.SilkS")
		)
		(fp_line
			(start 1.524 0.762)
			(end 1.524 -0.762)
			(stroke
				(width 0.1524)
				(type default)
			)
			(layer "B.SilkS")
		)
		(fp_line
			(start -1.524 -0.762)
			(end -1.524 0.762)
			(stroke
				(width 0.1524)
				(type default)
			)
			(layer "B.SilkS")
		)
		(fp_line
			(start 1.524 -0.762)
			(end -1.524 -0.762)
			(stroke
				(width 0.1524)
				(type default)
			)
			(layer "B.SilkS")
		)
		(fp_line
			(start -1.1049 0.724916)
			(end -1.1049 -0.724916)
			(stroke
				(width 0.1)
				(type default)
			)
			(layer "B.Fab")
		)
		(fp_line
			(start 1.1049 0.724916)
			(end -1.1049 0.724916)
			(stroke
				(width 0.1)
				(type default)
			)
			(layer "B.Fab")
		)
		(fp_line
			(start -1.1049 -0.724916)
			(end 1.1049 -0.724916)
			(stroke
				(width 0.1)
				(type default)
			)
			(layer "B.Fab")
		)
		(fp_line
			(start 1.1049 -0.724916)
			(end 1.1049 0.724916)
			(stroke
				(width 0.1)
				(type default)
			)
			(layer "B.Fab")
		)
		(pad "1" smd rect
			(at 0.889 0 270)
			(size 1.016 1.27)
			(layers "B.Cu" "B.Mask" "B.Paste")
			(net "SW_P12V_PVCCIN_CPU0_FLT")
		)
		(pad "2" smd rect
			(at -0.889 0 270)
			(size 1.016 1.27)
			(layers "B.Cu" "B.Mask" "B.Paste")
			(net "GND")
		)
	)
	(footprint ""
		(layer "B.Cu")
		(at 321.747642 -26.71064 -90)
		(property "Reference" "R621"
			(at 0 0 90)
			(layer "B.SilkS")
			(hide yes)
			(effects
				(font
					(size 1.27 1.27)
				)
				(justify mirror)
			)
		)
		(property "Value" ""
			(at 0 0 90)
			(layer "B.Fab")
			(effects
				(font
					(size 1.27 1.27)
				)
				(justify mirror)
			)
		)
		(duplicate_pad_numbers_are_jumpers no)
		(fp_line
			(start -0.7874 0.4064)
			(end 0.7874 0.4064)
			(stroke
				(width 0.1524)
				(type default)
			)
			(layer "B.SilkS")
		)
		(fp_line
			(start 0.7874 0.4064)
			(end 0.7874 -0.4064)
			(stroke
				(width 0.1524)
				(type default)
			)
			(layer "B.SilkS")
		)
		(fp_line
			(start -0.7874 -0.4064)
			(end -0.7874 0.4064)
			(stroke
				(width 0.1524)
				(type default)
			)
			(layer "B.SilkS")
		)
		(fp_line
			(start 0.7874 -0.4064)
			(end -0.7874 -0.4064)
			(stroke
				(width 0.1524)
				(type default)
			)
			(layer "B.SilkS")
		)
		(fp_line
			(start -0.67945 0.3048)
			(end -0.120396 0.3048)
			(stroke
				(width 0.1)
				(type default)
			)
			(layer "B.Fab")
		)
		(fp_line
			(start -0.120396 0.3048)
			(end -0.120396 0.2794)
			(stroke
				(width 0.1)
				(type default)
			)
			(layer "B.Fab")
		)
		(fp_line
			(start 0.12065 0.3048)
			(end 0.67945 0.3048)
			(stroke
				(width 0.1)
				(type default)
			)
			(layer "B.Fab")
		)
		(fp_line
			(start 0.67945 0.3048)
			(end 0.67945 -0.305054)
			(stroke
				(width 0.1)
				(type default)
			)
			(layer "B.Fab")
		)
		(fp_line
			(start -0.120396 0.2794)
			(end 0.12065 0.2794)
			(stroke
				(width 0.1)
				(type default)
			)
			(layer "B.Fab")
		)
		(fp_line
			(start 0.12065 0.2794)
			(end 0.12065 0.3048)
			(stroke
				(width 0.1)
				(type default)
			)
			(layer "B.Fab")
		)
		(fp_line
			(start -0.12065 -0.2794)
			(end -0.12065 -0.3048)
			(stroke
				(width 0.1)
				(type default)
			)
			(layer "B.Fab")
		)
		(fp_line
			(start 0.12065 -0.2794)
			(end -0.12065 -0.2794)
			(stroke
				(width 0.1)
				(type default)
			)
			(layer "B.Fab")
		)
		(fp_line
			(start -0.67945 -0.3048)
			(end -0.67945 0.3048)
			(stroke
				(width 0.1)
				(type default)
			)
			(layer "B.Fab")
		)
		(fp_line
			(start -0.12065 -0.3048)
			(end -0.67945 -0.3048)
			(stroke
				(width 0.1)
				(type default)
			)
			(layer "B.Fab")
		)
		(fp_line
			(start 0.12065 -0.305054)
			(end 0.12065 -0.2794)
			(stroke
				(width 0.1)
				(type default)
			)
			(layer "B.Fab")
		)
		(fp_line
			(start 0.67945 -0.305054)
			(end 0.12065 -0.305054)
			(stroke
				(width 0.1)
				(type default)
			)
			(layer "B.Fab")
		)
		(pad "1" smd circle
			(at 0.40005 0 90)
			(size 0 0)
			(layers "B.Cu" "B.Mask" "B.Paste")
			(net "P3V3_AUX")
		)
		(pad "2" smd circle
			(at -0.40005 0 90)
			(size 0 0)
			(layers "B.Cu" "B.Mask" "B.Paste")
			(net "FM_PCH_SKIP_RTC_CLOCK")
		)
	)
	(footprint ""
		(layer "B.Cu")
		(at 409.197556 -318.755776)
		(property "Reference" "R35"
			(at 0 0 0)
			(layer "B.SilkS")
			(hide yes)
			(effects
				(font
					(size 1.27 1.27)
				)
				(justify mirror)
			)
		)
		(property "Value" ""
			(at 0 0 0)
			(layer "B.Fab")
			(effects
				(font
					(size 1.27 1.27)
				)
				(justify mirror)
			)
		)
		(duplicate_pad_numbers_are_jumpers no)
		(fp_line
			(start -0.7874 -0.4064)
			(end -0.7874 0.4064)
			(stroke
				(width 0.1524)
				(type default)
			)
			(layer "B.SilkS")
		)
		(fp_line
			(start -0.7874 0.4064)
			(end 0.7874 0.4064)
			(stroke
				(width 0.1524)
				(type default)
			)
			(layer "B.SilkS")
		)
		(fp_line
			(start 0.7874 -0.4064)
			(end -0.7874 -0.4064)
			(stroke
				(width 0.1524)
				(type default)
			)
			(layer "B.SilkS")
		)
		(fp_line
			(start 0.7874 0.4064)
			(end 0.7874 -0.4064)
			(stroke
				(width 0.1524)
				(type default)
			)
			(layer "B.SilkS")
		)
		(fp_line
			(start -0.67945 -0.3048)
			(end -0.67945 0.3048)
			(stroke
				(width 0.1)
				(type default)
			)
			(layer "B.Fab")
		)
		(fp_line
			(start -0.67945 0.3048)
			(end -0.120396 0.3048)
			(stroke
				(width 0.1)
				(type default)
			)
			(layer "B.Fab")
		)
		(fp_line
			(start -0.12065 -0.3048)
			(end -0.67945 -0.3048)
			(stroke
				(width 0.1)
				(type default)
			)
			(layer "B.Fab")
		)
		(fp_line
			(start -0.12065 -0.2794)
			(end -0.12065 -0.3048)
			(stroke
				(width 0.1)
				(type default)
			)
			(layer "B.Fab")
		)
		(fp_line
			(start -0.120396 0.2794)
			(end 0.12065 0.2794)
			(stroke
				(width 0.1)
				(type default)
			)
			(layer "B.Fab")
		)
		(fp_line
			(start -0.120396 0.3048)
			(end -0.120396 0.2794)
			(stroke
				(width 0.1)
				(type default)
			)
			(layer "B.Fab")
		)
		(fp_line
			(start 0.12065 -0.305054)
			(end 0.12065 -0.2794)
			(stroke
				(width 0.1)
				(type default)
			)
			(layer "B.Fab")
		)
		(fp_line
			(start 0.12065 -0.2794)
			(end -0.12065 -0.2794)
			(stroke
				(width 0.1)
				(type default)
			)
			(layer "B.Fab")
		)
		(fp_line
			(start 0.12065 0.2794)
			(end 0.12065 0.3048)
			(stroke
				(width 0.1)
				(type default)
			)
			(layer "B.Fab")
		)
		(fp_line
			(start 0.12065 0.3048)
			(end 0.67945 0.3048)
			(stroke
				(width 0.1)
				(type default)
			)
			(layer "B.Fab")
		)
		(fp_line
			(start 0.67945 -0.305054)
			(end 0.12065 -0.305054)
			(stroke
				(width 0.1)
				(type default)
			)
			(layer "B.Fab")
		)
		(fp_line
			(start 0.67945 0.3048)
			(end 0.67945 -0.305054)
			(stroke
				(width 0.1)
				(type default)
			)
			(layer "B.Fab")
		)
		(pad "1" smd circle
			(at 0.40005 0 180)
			(size 0 0)
			(layers "B.Cu" "B.Mask" "B.Paste")
			(net "PD_CHE_CPU0_DIMM2_SAA")
		)
		(pad "2" smd circle
			(at -0.40005 0 180)
			(size 0 0)
			(layers "B.Cu" "B.Mask" "B.Paste")
			(net "GND")
		)
	)
)
